# T6G (Grand Teton) — schematic netlist excerpt (pin names and nets, part order shuffled) for the footprints in the layout excerpt that follows; sources: Cadence DE-HDL packaged netlist, KiCad conversion of 04192023_DAF0TMB3IC0_F0TG_MB_C_brd_V02_OCP.brd

R1728  Q_RES  10K 1% EMPTY  pkg 0402LF  page 171 : A = P3V3_AUX ; B = JTAG_SCM_TDI
R1046  Q_RES  0 5% EMPTY  pkg 0402LF  page 301 : A = P1V8_CPU0_RT2_1A_1D ; B = P1V8_CPU0_RT2_1A
R1472  Q_RES  1K 1% EMPTY  pkg 0201LF  page 287 : A = P1V8_CPU0_RT_1D ; B = JTAG_TDO_RT_CPU0_P1

(kicad_pcb
	(version 20260206)
	(generator "pcbnew")
	(generator_version "10.0")
	(general
		(thickness 1.6)
		(legacy_teardrops no)
	)
	(paper "A4")
	(title_block
		(title "04192023_DAF0TMB3IC0_F0TG_MB_C_brd_V02_OCP.brd")
		(comment 1 "Grand Teton / footprints 3597-3599 of 8354")
	)
	(layers
		(0 "F.Cu" signal "TOP")
		(4 "In1.Cu" signal "GND")
		(6 "In2.Cu" signal "IN1")
		(8 "In3.Cu" signal "GND1")
		(10 "In4.Cu" signal "IN2")
		(12 "In5.Cu" signal "GND2")
		(14 "In6.Cu" signal "IN3")
		(16 "In7.Cu" signal "GND3")
		(18 "In8.Cu" signal "VCC")
		(20 "In9.Cu" signal "VCC1")
		(22 "In10.Cu" signal "GND4")
		(24 "In11.Cu" signal "IN4")
		(26 "In12.Cu" signal "GND5")
		(28 "In13.Cu" signal "IN5")
		(30 "In14.Cu" signal "GND6")
		(32 "In15.Cu" signal "IN6")
		(34 "In16.Cu" signal "GND7")
		(2 "B.Cu" signal "BOTTOM")
		(9 "F.Adhes" user "F.Adhesive")
		(11 "B.Adhes" user "B.Adhesive")
		(13 "F.Paste" user "Package Geometry/Pastemask Top")
		(15 "B.Paste" user "Package Geometry/Pastemask Bottom")
		(5 "F.SilkS" user "Ref Des/Silkscreen Top")
		(7 "B.SilkS" user "Ref Des/Silkscreen Bottom")
		(1 "F.Mask" user "Board Geometry/Soldermask Top")
		(3 "B.Mask" user "Board Geometry/Soldermask Bottom")
		(17 "Dwgs.User" user "User.Drawings")
		(19 "Cmts.User" user "User.Comments")
		(21 "Eco1.User" user "User.Eco1")
		(23 "Eco2.User" user "User.Eco2")
		(25 "Edge.Cuts" user "Board Geometry/Outline")
		(27 "Margin" user)
		(31 "F.CrtYd" user "Package Geometry/Place Bound Top")
		(29 "B.CrtYd" user "Package Geometry/Place Bound Bottom")
		(35 "F.Fab" user "Ref Des/Assembly Top")
		(33 "B.Fab" user "Ref Des/Assembly Bottom")
	)
	(footprint ""
		(layer "F.Cu")
		(at 426.469556 -397.135604 180)
		(property "Reference" "R1046"
			(at 0 0 180)
			(layer "F.SilkS")
			(hide yes)
			(effects
				(font
					(size 1.27 1.27)
				)
			)
		)
		(property "Value" ""
			(at 0 0 180)
			(layer "F.Fab")
			(effects
				(font
					(size 1.27 1.27)
				)
			)
		)
		(duplicate_pad_numbers_are_jumpers no)
		(fp_line
			(start 0.7874 0.4064)
			(end -0.7874 0.4064)
			(stroke
				(width 0.1524)
				(type default)
			)
			(layer "F.SilkS")
		)
		(fp_line
			(start 0.7874 -0.4064)
			(end 0.7874 0.4064)
			(stroke
				(width 0.1524)
				(type default)
			)
			(layer "F.SilkS")
		)
		(fp_line
			(start -0.7874 0.4064)
			(end -0.7874 -0.4064)
			(stroke
				(width 0.1524)
				(type default)
			)
			(layer "F.SilkS")
		)
		(fp_line
			(start -0.7874 -0.4064)
			(end 0.7874 -0.4064)
			(stroke
				(width 0.1524)
				(type default)
			)
			(layer "F.SilkS")
		)
		(fp_line
			(start 0.67945 0.3048)
			(end 0.120396 0.3048)
			(stroke
				(width 0.1)
				(type default)
			)
			(layer "F.Fab")
		)
		(fp_line
			(start 0.67945 -0.3048)
			(end 0.67945 0.3048)
			(stroke
				(width 0.1)
				(type default)
			)
			(layer "F.Fab")
		)
		(fp_line
			(start 0.12065 -0.2794)
			(end 0.12065 -0.3048)
			(stroke
				(width 0.1)
				(type default)
			)
			(layer "F.Fab")
		)
		(fp_line
			(start 0.12065 -0.3048)
			(end 0.67945 -0.3048)
			(stroke
				(width 0.1)
				(type default)
			)
			(layer "F.Fab")
		)
		(fp_line
			(start 0.120396 0.3048)
			(end 0.120396 0.2794)
			(stroke
				(width 0.1)
				(type default)
			)
			(layer "F.Fab")
		)
		(fp_line
			(start 0.120396 0.2794)
			(end -0.12065 0.2794)
			(stroke
				(width 0.1)
				(type default)
			)
			(layer "F.Fab")
		)
		(fp_line
			(start -0.12065 0.3048)
			(end -0.67945 0.3048)
			(stroke
				(width 0.1)
				(type default)
			)
			(layer "F.Fab")
		)
		(fp_line
			(start -0.12065 0.2794)
			(end -0.12065 0.3048)
			(stroke
				(width 0.1)
				(type default)
			)
			(layer "F.Fab")
		)
		(fp_line
			(start -0.12065 -0.2794)
			(end 0.12065 -0.2794)
			(stroke
				(width 0.1)
				(type default)
			)
			(layer "F.Fab")
		)
		(fp_line
			(start -0.12065 -0.305054)
			(end -0.12065 -0.2794)
			(stroke
				(width 0.1)
				(type default)
			)
			(layer "F.Fab")
		)
		(fp_line
			(start -0.67945 0.3048)
			(end -0.67945 -0.305054)
			(stroke
				(width 0.1)
				(type default)
			)
			(layer "F.Fab")
		)
		(fp_line
			(start -0.67945 -0.305054)
			(end -0.12065 -0.305054)
			(stroke
				(width 0.1)
				(type default)
			)
			(layer "F.Fab")
		)
		(pad "1" smd rect
			(at -0.40005 0)
			(size 0.4572 0.508)
			(layers "F.Cu" "F.Mask" "F.Paste")
			(net "P1V8_CPU0_RT2_1A_1D")
		)
		(pad "2" smd rect
			(at 0.40005 0)
			(size 0.4572 0.508)
			(layers "F.Cu" "F.Mask" "F.Paste")
			(net "P1V8_CPU0_RT2_1A")
		)
	)
	(footprint ""
		(layer "F.Cu")
		(at 353.1108 -407.8732 90)
		(property "Reference" "R1472"
			(at 0 0 90)
			(layer "F.SilkS")
			(hide yes)
			(effects
				(font
					(size 1.27 1.27)
				)
			)
		)
		(property "Value" ""
			(at 0 0 90)
			(layer "F.Fab")
			(effects
				(font
					(size 1.27 1.27)
				)
			)
		)
		(duplicate_pad_numbers_are_jumpers no)
		(fp_line
			(start 0.32512 -0.175006)
			(end 0.32512 0.175006)
			(stroke
				(width 0.1)
				(type default)
			)
			(layer "F.Fab")
		)
		(fp_line
			(start -0.32512 -0.175006)
			(end 0.32512 -0.175006)
			(stroke
				(width 0.1)
				(type default)
			)
			(layer "F.Fab")
		)
		(fp_line
			(start 0.32512 0.175006)
			(end -0.32512 0.175006)
			(stroke
				(width 0.1)
				(type default)
			)
			(layer "F.Fab")
		)
		(fp_line
			(start -0.32512 0.175006)
			(end -0.32512 -0.175006)
			(stroke
				(width 0.1)
				(type default)
			)
			(layer "F.Fab")
		)
		(pad "1" smd rect
			(at -0.2667 0 90)
			(size 0.3048 0.381)
			(layers "F.Cu" "F.Mask" "F.Paste")
			(net "P1V8_CPU0_RT_1D")
		)
		(pad "2" smd rect
			(at 0.2667 0 270)
			(size 0.3048 0.381)
			(layers "F.Cu" "F.Mask" "F.Paste")
			(net "JTAG_TDO_RT_CPU0_P1")
		)
	)
	(footprint ""
		(layer "F.Cu")
		(at 138.426952 -59.83224 180)
		(property "Reference" "R1728"
			(at 0 0 180)
			(layer "F.SilkS")
			(hide yes)
			(effects
				(font
					(size 1.27 1.27)
				)
			)
		)
		(property "Value" ""
			(at 0 0 180)
			(layer "F.Fab")
			(effects
				(font
					(size 1.27 1.27)
				)
			)
		)
		(duplicate_pad_numbers_are_jumpers no)
		(fp_line
			(start 0.7874 0.4064)
			(end -0.7874 0.4064)
			(stroke
				(width 0.1524)
				(type default)
			)
			(layer "F.SilkS")
		)
		(fp_line
			(start 0.7874 -0.4064)
			(end 0.7874 0.4064)
			(stroke
				(width 0.1524)
				(type default)
			)
			(layer "F.SilkS")
		)
		(fp_line
			(start -0.7874 0.4064)
			(end -0.7874 -0.4064)
			(stroke
				(width 0.1524)
				(type default)
			)
			(layer "F.SilkS")
		)
		(fp_line
			(start -0.7874 -0.4064)
			(end 0.7874 -0.4064)
			(stroke
				(width 0.1524)
				(type default)
			)
			(layer "F.SilkS")
		)
		(fp_line
			(start 0.67945 0.3048)
			(end 0.120396 0.3048)
			(stroke
				(width 0.1)
				(type default)
			)
			(layer "F.Fab")
		)
		(fp_line
			(start 0.67945 -0.3048)
			(end 0.67945 0.3048)
			(stroke
				(width 0.1)
				(type default)
			)
			(layer "F.Fab")
		)
		(fp_line
			(start 0.12065 -0.2794)
			(end 0.12065 -0.3048)
			(stroke
				(width 0.1)
				(type default)
			)
			(layer "F.Fab")
		)
		(fp_line
			(start 0.12065 -0.3048)
			(end 0.67945 -0.3048)
			(stroke
				(width 0.1)
				(type default)
			)
			(layer "F.Fab")
		)
		(fp_line
			(start 0.120396 0.3048)
			(end 0.120396 0.2794)
			(stroke
				(width 0.1)
				(type default)
			)
			(layer "F.Fab")
		)
		(fp_line
			(start 0.120396 0.2794)
			(end -0.12065 0.2794)
			(stroke
				(width 0.1)
				(type default)
			)
			(layer "F.Fab")
		)
		(fp_line
			(start -0.12065 0.3048)
			(end -0.67945 0.3048)
			(stroke
				(width 0.1)
				(type default)
			)
			(layer "F.Fab")
		)
		(fp_line
			(start -0.12065 0.2794)
			(end -0.12065 0.3048)
			(stroke
				(width 0.1)
				(type default)
			)
			(layer "F.Fab")
		)
		(fp_line
			(start -0.12065 -0.2794)
			(end 0.12065 -0.2794)
			(stroke
				(width 0.1)
				(type default)
			)
			(layer "F.Fab")
		)
		(fp_line
			(start -0.12065 -0.305054)
			(end -0.12065 -0.2794)
			(stroke
				(width 0.1)
				(type default)
			)
			(layer "F.Fab")
		)
		(fp_line
			(start -0.67945 0.3048)
			(end -0.67945 -0.305054)
			(stroke
				(width 0.1)
				(type default)
			)
			(layer "F.Fab")
		)
		(fp_line
			(start -0.67945 -0.305054)
			(end -0.12065 -0.305054)
			(stroke
				(width 0.1)
				(type default)
			)
			(layer "F.Fab")
		)
		(pad "1" smd circle
			(at -0.40005 0 180)
			(size 0 0)
			(layers "F.Cu" "F.Mask" "F.Paste")
			(net "P3V3_AUX")
		)
		(pad "2" smd circle
			(at 0.40005 0 180)
			(size 0 0)
			(layers "F.Cu" "F.Mask" "F.Paste")
			(net "JTAG_SCM_TDI")
		)
	)
)
